(kicad_pcb
	(version 20260206)
	(generator "pcbnew")
	(generator_version "10.0")
	(general
		(thickness 1.6)
		(legacy_teardrops no)
	)
	(paper "A4")
	(title_block
		(title "01162023_DA0F0TEBIF0_F0T_Expander_BD_F_brd_V02_OCP.brd")
		(comment 1 "Grand Teton / footprints 6301-6306 of 9728")
	)
	(layers
		(0 "F.Cu" signal "TOP")
		(4 "In1.Cu" signal "GND")
		(6 "In2.Cu" signal "VCC")
		(8 "In3.Cu" signal "VCC1")
		(10 "In4.Cu" signal "GND1")
		(12 "In5.Cu" signal "IN1")
		(14 "In6.Cu" signal "GND2")
		(16 "In7.Cu" signal "IN2")
		(18 "In8.Cu" signal "GND3")
		(20 "In9.Cu" signal "IN3")
		(22 "In10.Cu" signal "GND4")
		(24 "In11.Cu" signal "IN4")
		(26 "In12.Cu" signal "GND5")
		(28 "In13.Cu" signal "IN5")
		(30 "In14.Cu" signal "GND6")
		(32 "In15.Cu" signal "IN6")
		(34 "In16.Cu" signal "GND7")
		(2 "B.Cu" signal "BOTTOM")
		(9 "F.Adhes" user "F.Adhesive")
		(11 "B.Adhes" user "B.Adhesive")
		(13 "F.Paste" user "Package Geometry/Pastemask Top")
		(15 "B.Paste" user "Package Geometry/Pastemask Bottom")
		(5 "F.SilkS" user "Ref Des/Silkscreen Top")
		(7 "B.SilkS" user "Ref Des/Silkscreen Bottom")
		(1 "F.Mask" user "Board Geometry/Soldermask Top")
		(3 "B.Mask" user "Board Geometry/Soldermask Bottom")
		(17 "Dwgs.User" user "User.Drawings")
		(19 "Cmts.User" user "User.Comments")
		(21 "Eco1.User" user "User.Eco1")
		(23 "Eco2.User" user "User.Eco2")
		(25 "Edge.Cuts" user "Board Geometry/Outline")
		(27 "Margin" user)
		(31 "F.CrtYd" user "Package Geometry/Place Bound Top")
		(29 "B.CrtYd" user "Package Geometry/Place Bound Bottom")
		(35 "F.Fab" user "Ref Des/Assembly Top")
		(33 "B.Fab" user "Ref Des/Assembly Bottom")
	)
	(footprint ""
		(layer "F.Cu")
		(at 420.87546 -69.47916 180)
		(property "Reference" "PU117"
			(at -2.03581 4.13004 90)
			(unlocked yes)
			(layer "F.SilkS")
			(effects
				(font
					(size 0.7874 0.5842)
					(thickness 0.1524)
				)
			)
		)
		(property "Value" ""
			(at 0 0 180)
			(layer "F.Fab")
			(effects
				(font
					(size 1.27 1.27)
				)
			)
		)
		(duplicate_pad_numbers_are_jumpers no)
		(fp_line
			(start 1.239774 1.495298)
			(end -1.239774 1.495298)
			(stroke
				(width 0.1524)
				(type default)
			)
			(layer "F.SilkS")
		)
		(fp_line
			(start 1.239774 -1.495298)
			(end 1.239774 1.495298)
			(stroke
				(width 0.1524)
				(type default)
			)
			(layer "F.SilkS")
		)
		(fp_line
			(start -1.239774 1.495298)
			(end -1.239774 -1.495298)
			(stroke
				(width 0.1524)
				(type default)
			)
			(layer "F.SilkS")
		)
		(fp_line
			(start -1.239774 -1.495298)
			(end 1.239774 -1.495298)
			(stroke
				(width 0.1524)
				(type default)
			)
			(layer "F.SilkS")
		)
		(fp_poly
			(pts
				(xy -1.713738 -1.337564) (xy -2.43205 -0.619252) (xy -1.354328 -0.260096)
			)
			(stroke
				(width 0)
				(type default)
			)
			(fill yes)
			(layer "F.SilkS")
		)
		(fp_line
			(start 0.8001 1.050036)
			(end -0.8001 1.050036)
			(stroke
				(width 0.1)
				(type default)
			)
			(layer "F.Fab")
		)
		(fp_line
			(start 0.8001 -1.050036)
			(end 0.8001 1.050036)
			(stroke
				(width 0.1)
				(type default)
			)
			(layer "F.Fab")
		)
		(fp_line
			(start -0.8001 1.050036)
			(end -0.8001 -1.050036)
			(stroke
				(width 0.1)
				(type default)
			)
			(layer "F.Fab")
		)
		(fp_line
			(start -0.8001 -1.050036)
			(end 0.8001 -1.050036)
			(stroke
				(width 0.1)
				(type default)
			)
			(layer "F.Fab")
		)
		(fp_poly
			(pts
				(xy -2.458974 -0.508) (xy -2.458974 0.508) (xy -1.442974 0)
			)
			(stroke
				(width 0)
				(type default)
			)
			(fill yes)
			(layer "F.Fab")
		)
		(pad "1_2" smd circle
			(at -0.374904 0 270)
			(size 0 0)
			(layers "F.Cu" "F.Mask" "F.Paste")
			(net "P12V_AUX")
		)
		(pad "3" smd rect
			(at -0.499872 0.999998 180)
			(size 0.254 0.7112)
			(layers "F.Cu" "F.Mask" "F.Paste")
			(net "GND")
		)
		(pad "4" smd rect
			(at 0 0.999998 180)
			(size 0.254 0.7112)
			(layers "F.Cu" "F.Mask" "F.Paste")
			(net "P12V_SSD14_CO_ILIMIT")
		)
		(pad "5" smd rect
			(at 0.499872 0.999998 180)
			(size 0.254 0.7112)
			(layers "F.Cu" "F.Mask" "F.Paste")
			(net "P12V_SSD14_CO_MODE")
		)
		(pad "6_7" smd circle
			(at 0.374904 0 90)
			(size 0 0)
			(layers "F.Cu" "F.Mask" "F.Paste")
			(net "P12V_SSD14_R")
		)
		(pad "8" smd rect
			(at 0.499872 -0.999998 180)
			(size 0.254 0.7112)
			(layers "F.Cu" "F.Mask" "F.Paste")
			(net "P12V_SSD14_CO_GATE")
		)
		(pad "9" smd rect
			(at 0 -0.999998 180)
			(size 0.254 0.7112)
			(layers "F.Cu" "F.Mask" "F.Paste")
			(net "P12V_SSD14_CO_EN")
		)
		(pad "10" smd rect
			(at -0.499872 -0.999998 180)
			(size 0.254 0.7112)
			(layers "F.Cu" "F.Mask" "F.Paste")
			(net "P12V_SSD14_CO_DV_DT")
		)
	)
	(footprint ""
		(layer "F.Cu")
		(at 355.403404 -59.571636 90)
		(property "Reference" "PR274"
			(at 0 0 90)
			(layer "F.SilkS")
			(hide yes)
			(effects
				(font
					(size 1.27 1.27)
				)
			)
		)
		(property "Value" ""
			(at 0 0 90)
			(layer "F.Fab")
			(effects
				(font
					(size 1.27 1.27)
				)
			)
		)
		(duplicate_pad_numbers_are_jumpers no)
		(fp_line
			(start 0.7874 -0.4064)
			(end 0.7874 0.4064)
			(stroke
				(width 0.1524)
				(type default)
			)
			(layer "F.SilkS")
		)
		(fp_line
			(start -0.7874 -0.4064)
			(end 0.7874 -0.4064)
			(stroke
				(width 0.1524)
				(type default)
			)
			(layer "F.SilkS")
		)
		(fp_line
			(start 0.7874 0.4064)
			(end -0.7874 0.4064)
			(stroke
				(width 0.1524)
				(type default)
			)
			(layer "F.SilkS")
		)
		(fp_line
			(start -0.7874 0.4064)
			(end -0.7874 -0.4064)
			(stroke
				(width 0.1524)
				(type default)
			)
			(layer "F.SilkS")
		)
		(fp_line
			(start -0.12065 -0.305054)
			(end -0.12065 -0.2794)
			(stroke
				(width 0.1)
				(type default)
			)
			(layer "F.Fab")
		)
		(fp_line
			(start -0.67945 -0.305054)
			(end -0.12065 -0.305054)
			(stroke
				(width 0.1)
				(type default)
			)
			(layer "F.Fab")
		)
		(fp_line
			(start 0.67945 -0.3048)
			(end 0.67945 0.3048)
			(stroke
				(width 0.1)
				(type default)
			)
			(layer "F.Fab")
		)
		(fp_line
			(start 0.12065 -0.3048)
			(end 0.67945 -0.3048)
			(stroke
				(width 0.1)
				(type default)
			)
			(layer "F.Fab")
		)
		(fp_line
			(start 0.12065 -0.2794)
			(end 0.12065 -0.3048)
			(stroke
				(width 0.1)
				(type default)
			)
			(layer "F.Fab")
		)
		(fp_line
			(start -0.12065 -0.2794)
			(end 0.12065 -0.2794)
			(stroke
				(width 0.1)
				(type default)
			)
			(layer "F.Fab")
		)
		(fp_line
			(start 0.120396 0.2794)
			(end -0.12065 0.2794)
			(stroke
				(width 0.1)
				(type default)
			)
			(layer "F.Fab")
		)
		(fp_line
			(start -0.12065 0.2794)
			(end -0.12065 0.3048)
			(stroke
				(width 0.1)
				(type default)
			)
			(layer "F.Fab")
		)
		(fp_line
			(start 0.67945 0.3048)
			(end 0.120396 0.3048)
			(stroke
				(width 0.1)
				(type default)
			)
			(layer "F.Fab")
		)
		(fp_line
			(start 0.120396 0.3048)
			(end 0.120396 0.2794)
			(stroke
				(width 0.1)
				(type default)
			)
			(layer "F.Fab")
		)
		(fp_line
			(start -0.12065 0.3048)
			(end -0.67945 0.3048)
			(stroke
				(width 0.1)
				(type default)
			)
			(layer "F.Fab")
		)
		(fp_line
			(start -0.67945 0.3048)
			(end -0.67945 -0.305054)
			(stroke
				(width 0.1)
				(type default)
			)
			(layer "F.Fab")
		)
		(pad "1" smd circle
			(at -0.40005 0 90)
			(size 0 0)
			(layers "F.Cu" "F.Mask" "F.Paste")
			(net "P3V3_SSD12_OCP")
		)
		(pad "2" smd circle
			(at 0.40005 0 90)
			(size 0 0)
			(layers "F.Cu" "F.Mask" "F.Paste")
			(net "GND")
		)
	)
	(footprint ""
		(layer "F.Cu")
		(at 350.380554 -83.787234)
		(property "Reference" "R1596"
			(at 0 0 0)
			(layer "F.SilkS")
			(hide yes)
			(effects
				(font
					(size 1.27 1.27)
				)
			)
		)
		(property "Value" ""
			(at 0 0 0)
			(layer "F.Fab")
			(effects
				(font
					(size 1.27 1.27)
				)
			)
		)
		(duplicate_pad_numbers_are_jumpers no)
		(fp_line
			(start -0.7874 -0.4064)
			(end 0.7874 -0.4064)
			(stroke
				(width 0.1524)
				(type default)
			)
			(layer "F.SilkS")
		)
		(fp_line
			(start -0.7874 0.4064)
			(end -0.7874 -0.4064)
			(stroke
				(width 0.1524)
				(type default)
			)
			(layer "F.SilkS")
		)
		(fp_line
			(start 0.7874 -0.4064)
			(end 0.7874 0.4064)
			(stroke
				(width 0.1524)
				(type default)
			)
			(layer "F.SilkS")
		)
		(fp_line
			(start 0.7874 0.4064)
			(end -0.7874 0.4064)
			(stroke
				(width 0.1524)
				(type default)
			)
			(layer "F.SilkS")
		)
		(fp_line
			(start -0.67945 -0.305054)
			(end -0.12065 -0.305054)
			(stroke
				(width 0.1)
				(type default)
			)
			(layer "F.Fab")
		)
		(fp_line
			(start -0.67945 0.3048)
			(end -0.67945 -0.305054)
			(stroke
				(width 0.1)
				(type default)
			)
			(layer "F.Fab")
		)
		(fp_line
			(start -0.12065 -0.305054)
			(end -0.12065 -0.2794)
			(stroke
				(width 0.1)
				(type default)
			)
			(layer "F.Fab")
		)
		(fp_line
			(start -0.12065 -0.2794)
			(end 0.12065 -0.2794)
			(stroke
				(width 0.1)
				(type default)
			)
			(layer "F.Fab")
		)
		(fp_line
			(start -0.12065 0.2794)
			(end -0.12065 0.3048)
			(stroke
				(width 0.1)
				(type default)
			)
			(layer "F.Fab")
		)
		(fp_line
			(start -0.12065 0.3048)
			(end -0.67945 0.3048)
			(stroke
				(width 0.1)
				(type default)
			)
			(layer "F.Fab")
		)
		(fp_line
			(start 0.120396 0.2794)
			(end -0.12065 0.2794)
			(stroke
				(width 0.1)
				(type default)
			)
			(layer "F.Fab")
		)
		(fp_line
			(start 0.120396 0.3048)
			(end 0.120396 0.2794)
			(stroke
				(width 0.1)
				(type default)
			)
			(layer "F.Fab")
		)
		(fp_line
			(start 0.12065 -0.3048)
			(end 0.67945 -0.3048)
			(stroke
				(width 0.1)
				(type default)
			)
			(layer "F.Fab")
		)
		(fp_line
			(start 0.12065 -0.2794)
			(end 0.12065 -0.3048)
			(stroke
				(width 0.1)
				(type default)
			)
			(layer "F.Fab")
		)
		(fp_line
			(start 0.67945 -0.3048)
			(end 0.67945 0.3048)
			(stroke
				(width 0.1)
				(type default)
			)
			(layer "F.Fab")
		)
		(fp_line
			(start 0.67945 0.3048)
			(end 0.120396 0.3048)
			(stroke
				(width 0.1)
				(type default)
			)
			(layer "F.Fab")
		)
		(pad "1" smd circle
			(at -0.40005 0)
			(size 0 0)
			(layers "F.Cu" "F.Mask" "F.Paste")
			(net "P3V3_AUX")
		)
		(pad "2" smd circle
			(at 0.40005 0)
			(size 0 0)
			(layers "F.Cu" "F.Mask" "F.Paste")
			(net "SMB_BIC_I2C9_MUX1_SSD10_R_SCL")
		)
	)
	(footprint ""
		(layer "F.Cu")
		(at 294.50919 -213.523068 -90)
		(property "Reference" "R3401"
			(at 0 0 270)
			(layer "F.SilkS")
			(hide yes)
			(effects
				(font
					(size 1.27 1.27)
				)
			)
		)
		(property "Value" ""
			(at 0 0 270)
			(layer "F.Fab")
			(effects
				(font
					(size 1.27 1.27)
				)
			)
		)
		(duplicate_pad_numbers_are_jumpers no)
		(fp_line
			(start -0.7874 0.4064)
			(end -0.7874 -0.4064)
			(stroke
				(width 0.1524)
				(type default)
			)
			(layer "F.SilkS")
		)
		(fp_line
			(start 0.7874 0.4064)
			(end -0.7874 0.4064)
			(stroke
				(width 0.1524)
				(type default)
			)
			(layer "F.SilkS")
		)
		(fp_line
			(start -0.7874 -0.4064)
			(end 0.7874 -0.4064)
			(stroke
				(width 0.1524)
				(type default)
			)
			(layer "F.SilkS")
		)
		(fp_line
			(start 0.7874 -0.4064)
			(end 0.7874 0.4064)
			(stroke
				(width 0.1524)
				(type default)
			)
			(layer "F.SilkS")
		)
		(fp_line
			(start -0.67945 0.3048)
			(end -0.67945 -0.305054)
			(stroke
				(width 0.1)
				(type default)
			)
			(layer "F.Fab")
		)
		(fp_line
			(start -0.12065 0.3048)
			(end -0.67945 0.3048)
			(stroke
				(width 0.1)
				(type default)
			)
			(layer "F.Fab")
		)
		(fp_line
			(start 0.120396 0.3048)
			(end 0.120396 0.2794)
			(stroke
				(width 0.1)
				(type default)
			)
			(layer "F.Fab")
		)
		(fp_line
			(start 0.67945 0.3048)
			(end 0.120396 0.3048)
			(stroke
				(width 0.1)
				(type default)
			)
			(layer "F.Fab")
		)
		(fp_line
			(start -0.12065 0.2794)
			(end -0.12065 0.3048)
			(stroke
				(width 0.1)
				(type default)
			)
			(layer "F.Fab")
		)
		(fp_line
			(start 0.120396 0.2794)
			(end -0.12065 0.2794)
			(stroke
				(width 0.1)
				(type default)
			)
			(layer "F.Fab")
		)
		(fp_line
			(start -0.12065 -0.2794)
			(end 0.12065 -0.2794)
			(stroke
				(width 0.1)
				(type default)
			)
			(layer "F.Fab")
		)
		(fp_line
			(start 0.12065 -0.2794)
			(end 0.12065 -0.3048)
			(stroke
				(width 0.1)
				(type default)
			)
			(layer "F.Fab")
		)
		(fp_line
			(start 0.12065 -0.3048)
			(end 0.67945 -0.3048)
			(stroke
				(width 0.1)
				(type default)
			)
			(layer "F.Fab")
		)
		(fp_line
			(start 0.67945 -0.3048)
			(end 0.67945 0.3048)
			(stroke
				(width 0.1)
				(type default)
			)
			(layer "F.Fab")
		)
		(fp_line
			(start -0.67945 -0.305054)
			(end -0.12065 -0.305054)
			(stroke
				(width 0.1)
				(type default)
			)
			(layer "F.Fab")
		)
		(fp_line
			(start -0.12065 -0.305054)
			(end -0.12065 -0.2794)
			(stroke
				(width 0.1)
				(type default)
			)
			(layer "F.Fab")
		)
		(pad "1" smd circle
			(at -0.40005 0 270)
			(size 0 0)
			(layers "F.Cu" "F.Mask" "F.Paste")
			(net "SPI_BIC1_MISO_LS23_R2")
		)
		(pad "2" smd circle
			(at 0.40005 0 270)
			(size 0 0)
			(layers "F.Cu" "F.Mask" "F.Paste")
			(net "SPI_BIC1_MISO_LS23_R")
		)
	)
	(footprint ""
		(layer "F.Cu")
		(at 212.0265 -25.432004 -90)
		(property "Reference" "C972"
			(at 0 0 270)
			(layer "F.SilkS")
			(hide yes)
			(effects
				(font
					(size 1.27 1.27)
				)
			)
		)
		(property "Value" ""
			(at 0 0 270)
			(layer "F.Fab")
			(effects
				(font
					(size 1.27 1.27)
				)
			)
		)
		(duplicate_pad_numbers_are_jumpers no)
		(fp_line
			(start -0.7874 0.4064)
			(end -0.7874 -0.4064)
			(stroke
				(width 0.1524)
				(type default)
			)
			(layer "F.SilkS")
		)
		(fp_line
			(start 0.7874 0.4064)
			(end -0.7874 0.4064)
			(stroke
				(width 0.1524)
				(type default)
			)
			(layer "F.SilkS")
		)
		(fp_line
			(start -0.7874 -0.4064)
			(end 0.7874 -0.4064)
			(stroke
				(width 0.1524)
				(type default)
			)
			(layer "F.SilkS")
		)
		(fp_line
			(start 0.7874 -0.4064)
			(end 0.7874 0.4064)
			(stroke
				(width 0.1524)
				(type default)
			)
			(layer "F.SilkS")
		)
		(fp_line
			(start -0.67945 0.3048)
			(end -0.67945 -0.305054)
			(stroke
				(width 0.1)
				(type default)
			)
			(layer "F.Fab")
		)
		(fp_line
			(start -0.12065 0.3048)
			(end -0.67945 0.3048)
			(stroke
				(width 0.1)
				(type default)
			)
			(layer "F.Fab")
		)
		(fp_line
			(start 0.120396 0.3048)
			(end 0.120396 0.2794)
			(stroke
				(width 0.1)
				(type default)
			)
			(layer "F.Fab")
		)
		(fp_line
			(start 0.67945 0.3048)
			(end 0.120396 0.3048)
			(stroke
				(width 0.1)
				(type default)
			)
			(layer "F.Fab")
		)
		(fp_line
			(start -0.12065 0.2794)
			(end -0.12065 0.3048)
			(stroke
				(width 0.1)
				(type default)
			)
			(layer "F.Fab")
		)
		(fp_line
			(start 0.120396 0.2794)
			(end -0.12065 0.2794)
			(stroke
				(width 0.1)
				(type default)
			)
			(layer "F.Fab")
		)
		(fp_line
			(start -0.12065 -0.2794)
			(end 0.12065 -0.2794)
			(stroke
				(width 0.1)
				(type default)
			)
			(layer "F.Fab")
		)
		(fp_line
			(start 0.12065 -0.2794)
			(end 0.12065 -0.3048)
			(stroke
				(width 0.1)
				(type default)
			)
			(layer "F.Fab")
		)
		(fp_line
			(start 0.12065 -0.3048)
			(end 0.67945 -0.3048)
			(stroke
				(width 0.1)
				(type default)
			)
			(layer "F.Fab")
		)
		(fp_line
			(start 0.67945 -0.3048)
			(end 0.67945 0.3048)
			(stroke
				(width 0.1)
				(type default)
			)
			(layer "F.Fab")
		)
		(fp_line
			(start -0.67945 -0.305054)
			(end -0.12065 -0.305054)
			(stroke
				(width 0.1)
				(type default)
			)
			(layer "F.Fab")
		)
		(fp_line
			(start -0.12065 -0.305054)
			(end -0.12065 -0.2794)
			(stroke
				(width 0.1)
				(type default)
			)
			(layer "F.Fab")
		)
		(pad "1" smd circle
			(at -0.40005 0 270)
			(size 0 0)
			(layers "F.Cu" "F.Mask" "F.Paste")
			(net "GND")
		)
		(pad "2" smd circle
			(at 0.40005 0 270)
			(size 0 0)
			(layers "F.Cu" "F.Mask" "F.Paste")
			(net "P3V3_SSD7")
		)
	)
	(footprint ""
		(layer "F.Cu")
		(at 61.346842 -350.098614 90)
		(property "Reference" "C127"
			(at 0 0 90)
			(layer "F.SilkS")
			(hide yes)
			(effects
				(font
					(size 1.27 1.27)
				)
			)
		)
		(property "Value" ""
			(at 0 0 90)
			(layer "F.Fab")
			(effects
				(font
					(size 1.27 1.27)
				)
			)
		)
		(duplicate_pad_numbers_are_jumpers no)
		(fp_line
			(start 0.299974 -0.150114)
			(end 0.299974 0.150114)
			(stroke
				(width 0.1)
				(type default)
			)
			(layer "F.Fab")
		)
		(fp_line
			(start -0.299974 -0.150114)
			(end 0.299974 -0.150114)
			(stroke
				(width 0.1)
				(type default)
			)
			(layer "F.Fab")
		)
		(fp_line
			(start 0.299974 0.150114)
			(end -0.299974 0.150114)
			(stroke
				(width 0.1)
				(type default)
			)
			(layer "F.Fab")
		)
		(fp_line
			(start -0.299974 0.150114)
			(end -0.299974 -0.150114)
			(stroke
				(width 0.1)
				(type default)
			)
			(layer "F.Fab")
		)
		(pad "1" smd rect
			(at -0.2667 0 90)
			(size 0.3048 0.381)
			(layers "F.Cu" "F.Mask" "F.Paste")
			(net "P5E_PEX0_STN5_TX_DP<80>")
		)
		(pad "2" smd rect
			(at 0.2667 0 90)
			(size 0.3048 0.381)
			(layers "F.Cu" "F.Mask" "F.Paste")
			(net "P5E_PEX0_STN5_TX_C_DP<80>")
		)
	)
)
